(kicad_pcb
	(version 20260206)
	(generator "pcbnew")
	(generator_version "10.0")
	(general
		(thickness 1.6)
		(legacy_teardrops no)
	)
	(paper "A4")
	(title_block
		(title "12092022_DA0F0TMDCD0_F0T_Management_Board_D_brd_V3_OCP.brd")
		(comment 1 "Grand Teton / footprints 909-914 of 1440")
	)
	(layers
		(0 "F.Cu" signal "TOP")
		(4 "In1.Cu" signal "GND")
		(6 "In2.Cu" signal "IN1")
		(8 "In3.Cu" signal "GND1")
		(10 "In4.Cu" signal "IN2")
		(12 "In5.Cu" signal "VCC")
		(14 "In6.Cu" signal "VCC1")
		(16 "In7.Cu" signal "IN3")
		(18 "In8.Cu" signal "GND2")
		(20 "In9.Cu" signal "IN4")
		(22 "In10.Cu" signal "GND3")
		(2 "B.Cu" signal "BOTTOM")
		(9 "F.Adhes" user "F.Adhesive")
		(11 "B.Adhes" user "B.Adhesive")
		(13 "F.Paste" user "Package Geometry/Pastemask Top")
		(15 "B.Paste" user "Package Geometry/Pastemask Bottom")
		(5 "F.SilkS" user "Ref Des/Silkscreen Top")
		(7 "B.SilkS" user "Ref Des/Silkscreen Bottom")
		(1 "F.Mask" user "Board Geometry/Soldermask Top")
		(3 "B.Mask" user "Board Geometry/Soldermask Bottom")
		(17 "Dwgs.User" user "User.Drawings")
		(19 "Cmts.User" user "User.Comments")
		(21 "Eco1.User" user "User.Eco1")
		(23 "Eco2.User" user "User.Eco2")
		(25 "Edge.Cuts" user "Board Geometry/Outline")
		(27 "Margin" user)
		(31 "F.CrtYd" user "Package Geometry/Place Bound Top")
		(29 "B.CrtYd" user "Package Geometry/Place Bound Bottom")
		(35 "F.Fab" user "Ref Des/Assembly Top")
		(33 "B.Fab" user "Ref Des/Assembly Bottom")
	)
	(footprint ""
		(layer "B.Cu")
		(at 47.55388 -88.265 90)
		(property "Reference" "R770"
			(at 0 0 90)
			(layer "B.SilkS")
			(hide yes)
			(effects
				(font
					(size 1.27 1.27)
				)
				(justify mirror)
			)
		)
		(property "Value" ""
			(at 0 0 90)
			(layer "B.Fab")
			(effects
				(font
					(size 1.27 1.27)
				)
				(justify mirror)
			)
		)
		(duplicate_pad_numbers_are_jumpers no)
		(fp_line
			(start 0.7874 -0.4064)
			(end -0.7874 -0.4064)
			(stroke
				(width 0.1524)
				(type default)
			)
			(layer "B.SilkS")
		)
		(fp_line
			(start -0.7874 -0.4064)
			(end -0.7874 0.4064)
			(stroke
				(width 0.1524)
				(type default)
			)
			(layer "B.SilkS")
		)
		(fp_line
			(start 0.7874 0.4064)
			(end 0.7874 -0.4064)
			(stroke
				(width 0.1524)
				(type default)
			)
			(layer "B.SilkS")
		)
		(fp_line
			(start -0.7874 0.4064)
			(end 0.7874 0.4064)
			(stroke
				(width 0.1524)
				(type default)
			)
			(layer "B.SilkS")
		)
		(fp_line
			(start 0.67945 -0.305054)
			(end 0.12065 -0.305054)
			(stroke
				(width 0.1)
				(type default)
			)
			(layer "B.Fab")
		)
		(fp_line
			(start 0.12065 -0.305054)
			(end 0.12065 -0.2794)
			(stroke
				(width 0.1)
				(type default)
			)
			(layer "B.Fab")
		)
		(fp_line
			(start -0.12065 -0.3048)
			(end -0.67945 -0.3048)
			(stroke
				(width 0.1)
				(type default)
			)
			(layer "B.Fab")
		)
		(fp_line
			(start -0.67945 -0.3048)
			(end -0.67945 0.3048)
			(stroke
				(width 0.1)
				(type default)
			)
			(layer "B.Fab")
		)
		(fp_line
			(start 0.12065 -0.2794)
			(end -0.12065 -0.2794)
			(stroke
				(width 0.1)
				(type default)
			)
			(layer "B.Fab")
		)
		(fp_line
			(start -0.12065 -0.2794)
			(end -0.12065 -0.3048)
			(stroke
				(width 0.1)
				(type default)
			)
			(layer "B.Fab")
		)
		(fp_line
			(start 0.12065 0.2794)
			(end 0.12065 0.3048)
			(stroke
				(width 0.1)
				(type default)
			)
			(layer "B.Fab")
		)
		(fp_line
			(start -0.120396 0.2794)
			(end 0.12065 0.2794)
			(stroke
				(width 0.1)
				(type default)
			)
			(layer "B.Fab")
		)
		(fp_line
			(start 0.67945 0.3048)
			(end 0.67945 -0.305054)
			(stroke
				(width 0.1)
				(type default)
			)
			(layer "B.Fab")
		)
		(fp_line
			(start 0.12065 0.3048)
			(end 0.67945 0.3048)
			(stroke
				(width 0.1)
				(type default)
			)
			(layer "B.Fab")
		)
		(fp_line
			(start -0.120396 0.3048)
			(end -0.120396 0.2794)
			(stroke
				(width 0.1)
				(type default)
			)
			(layer "B.Fab")
		)
		(fp_line
			(start -0.67945 0.3048)
			(end -0.120396 0.3048)
			(stroke
				(width 0.1)
				(type default)
			)
			(layer "B.Fab")
		)
		(pad "1" smd circle
			(at 0.40005 0 270)
			(size 0 0)
			(layers "B.Cu" "B.Mask" "B.Paste")
			(net "GND")
		)
		(pad "2" smd circle
			(at -0.40005 0 270)
			(size 0 0)
			(layers "B.Cu" "B.Mask" "B.Paste")
			(net "UART_BMC_5_TXD_R")
		)
	)
	(footprint ""
		(layer "B.Cu")
		(at 24.590756 -106.50982 -90)
		(property "Reference" "R44"
			(at 0 0 90)
			(layer "B.SilkS")
			(hide yes)
			(effects
				(font
					(size 1.27 1.27)
				)
				(justify mirror)
			)
		)
		(property "Value" ""
			(at 0 0 90)
			(layer "B.Fab")
			(effects
				(font
					(size 1.27 1.27)
				)
				(justify mirror)
			)
		)
		(duplicate_pad_numbers_are_jumpers no)
		(fp_line
			(start -0.7874 0.4064)
			(end 0.7874 0.4064)
			(stroke
				(width 0.1524)
				(type default)
			)
			(layer "B.SilkS")
		)
		(fp_line
			(start 0.7874 0.4064)
			(end 0.7874 -0.4064)
			(stroke
				(width 0.1524)
				(type default)
			)
			(layer "B.SilkS")
		)
		(fp_line
			(start -0.7874 -0.4064)
			(end -0.7874 0.4064)
			(stroke
				(width 0.1524)
				(type default)
			)
			(layer "B.SilkS")
		)
		(fp_line
			(start 0.7874 -0.4064)
			(end -0.7874 -0.4064)
			(stroke
				(width 0.1524)
				(type default)
			)
			(layer "B.SilkS")
		)
		(fp_line
			(start -0.67945 0.3048)
			(end -0.120396 0.3048)
			(stroke
				(width 0.1)
				(type default)
			)
			(layer "B.Fab")
		)
		(fp_line
			(start -0.120396 0.3048)
			(end -0.120396 0.2794)
			(stroke
				(width 0.1)
				(type default)
			)
			(layer "B.Fab")
		)
		(fp_line
			(start 0.12065 0.3048)
			(end 0.67945 0.3048)
			(stroke
				(width 0.1)
				(type default)
			)
			(layer "B.Fab")
		)
		(fp_line
			(start 0.67945 0.3048)
			(end 0.67945 -0.305054)
			(stroke
				(width 0.1)
				(type default)
			)
			(layer "B.Fab")
		)
		(fp_line
			(start -0.120396 0.2794)
			(end 0.12065 0.2794)
			(stroke
				(width 0.1)
				(type default)
			)
			(layer "B.Fab")
		)
		(fp_line
			(start 0.12065 0.2794)
			(end 0.12065 0.3048)
			(stroke
				(width 0.1)
				(type default)
			)
			(layer "B.Fab")
		)
		(fp_line
			(start -0.12065 -0.2794)
			(end -0.12065 -0.3048)
			(stroke
				(width 0.1)
				(type default)
			)
			(layer "B.Fab")
		)
		(fp_line
			(start 0.12065 -0.2794)
			(end -0.12065 -0.2794)
			(stroke
				(width 0.1)
				(type default)
			)
			(layer "B.Fab")
		)
		(fp_line
			(start -0.67945 -0.3048)
			(end -0.67945 0.3048)
			(stroke
				(width 0.1)
				(type default)
			)
			(layer "B.Fab")
		)
		(fp_line
			(start -0.12065 -0.3048)
			(end -0.67945 -0.3048)
			(stroke
				(width 0.1)
				(type default)
			)
			(layer "B.Fab")
		)
		(fp_line
			(start 0.12065 -0.305054)
			(end 0.12065 -0.2794)
			(stroke
				(width 0.1)
				(type default)
			)
			(layer "B.Fab")
		)
		(fp_line
			(start 0.67945 -0.305054)
			(end 0.12065 -0.305054)
			(stroke
				(width 0.1)
				(type default)
			)
			(layer "B.Fab")
		)
		(pad "1" smd circle
			(at 0.40005 0 90)
			(size 0 0)
			(layers "B.Cu" "B.Mask" "B.Paste")
			(net "P3V3_AUX")
		)
		(pad "2" smd circle
			(at -0.40005 0 90)
			(size 0 0)
			(layers "B.Cu" "B.Mask" "B.Paste")
			(net "SYS_PWRBTN_N")
		)
	)
	(footprint ""
		(layer "B.Cu")
		(at 52.578 -34.6456 -90)
		(property "Reference" "R158"
			(at 0 0 90)
			(layer "B.SilkS")
			(hide yes)
			(effects
				(font
					(size 1.27 1.27)
				)
				(justify mirror)
			)
		)
		(property "Value" ""
			(at 0 0 90)
			(layer "B.Fab")
			(effects
				(font
					(size 1.27 1.27)
				)
				(justify mirror)
			)
		)
		(duplicate_pad_numbers_are_jumpers no)
		(fp_line
			(start -0.7874 0.4064)
			(end 0.7874 0.4064)
			(stroke
				(width 0.1524)
				(type default)
			)
			(layer "B.SilkS")
		)
		(fp_line
			(start 0.7874 0.4064)
			(end 0.7874 -0.4064)
			(stroke
				(width 0.1524)
				(type default)
			)
			(layer "B.SilkS")
		)
		(fp_line
			(start -0.7874 -0.4064)
			(end -0.7874 0.4064)
			(stroke
				(width 0.1524)
				(type default)
			)
			(layer "B.SilkS")
		)
		(fp_line
			(start 0.7874 -0.4064)
			(end -0.7874 -0.4064)
			(stroke
				(width 0.1524)
				(type default)
			)
			(layer "B.SilkS")
		)
		(fp_line
			(start -0.67945 0.3048)
			(end -0.120396 0.3048)
			(stroke
				(width 0.1)
				(type default)
			)
			(layer "B.Fab")
		)
		(fp_line
			(start -0.120396 0.3048)
			(end -0.120396 0.2794)
			(stroke
				(width 0.1)
				(type default)
			)
			(layer "B.Fab")
		)
		(fp_line
			(start 0.12065 0.3048)
			(end 0.67945 0.3048)
			(stroke
				(width 0.1)
				(type default)
			)
			(layer "B.Fab")
		)
		(fp_line
			(start 0.67945 0.3048)
			(end 0.67945 -0.305054)
			(stroke
				(width 0.1)
				(type default)
			)
			(layer "B.Fab")
		)
		(fp_line
			(start -0.120396 0.2794)
			(end 0.12065 0.2794)
			(stroke
				(width 0.1)
				(type default)
			)
			(layer "B.Fab")
		)
		(fp_line
			(start 0.12065 0.2794)
			(end 0.12065 0.3048)
			(stroke
				(width 0.1)
				(type default)
			)
			(layer "B.Fab")
		)
		(fp_line
			(start -0.12065 -0.2794)
			(end -0.12065 -0.3048)
			(stroke
				(width 0.1)
				(type default)
			)
			(layer "B.Fab")
		)
		(fp_line
			(start 0.12065 -0.2794)
			(end -0.12065 -0.2794)
			(stroke
				(width 0.1)
				(type default)
			)
			(layer "B.Fab")
		)
		(fp_line
			(start -0.67945 -0.3048)
			(end -0.67945 0.3048)
			(stroke
				(width 0.1)
				(type default)
			)
			(layer "B.Fab")
		)
		(fp_line
			(start -0.12065 -0.3048)
			(end -0.67945 -0.3048)
			(stroke
				(width 0.1)
				(type default)
			)
			(layer "B.Fab")
		)
		(fp_line
			(start 0.12065 -0.305054)
			(end 0.12065 -0.2794)
			(stroke
				(width 0.1)
				(type default)
			)
			(layer "B.Fab")
		)
		(fp_line
			(start 0.67945 -0.305054)
			(end 0.12065 -0.305054)
			(stroke
				(width 0.1)
				(type default)
			)
			(layer "B.Fab")
		)
		(pad "1" smd circle
			(at 0.40005 0 90)
			(size 0 0)
			(layers "B.Cu" "B.Mask" "B.Paste")
			(net "FM_DBP_CPU_PREQ_GF_R_N")
		)
		(pad "2" smd circle
			(at -0.40005 0 90)
			(size 0 0)
			(layers "B.Cu" "B.Mask" "B.Paste")
			(net "FM_DBP_CPU_PREQ_GF_N")
		)
	)
	(footprint ""
		(layer "B.Cu")
		(at 17.18056 -85.14588)
		(property "Reference" "R270"
			(at 0 0 0)
			(layer "B.SilkS")
			(hide yes)
			(effects
				(font
					(size 1.27 1.27)
				)
				(justify mirror)
			)
		)
		(property "Value" ""
			(at 0 0 0)
			(layer "B.Fab")
			(effects
				(font
					(size 1.27 1.27)
				)
				(justify mirror)
			)
		)
		(duplicate_pad_numbers_are_jumpers no)
		(fp_line
			(start -0.7874 -0.4064)
			(end -0.7874 0.4064)
			(stroke
				(width 0.1524)
				(type default)
			)
			(layer "B.SilkS")
		)
		(fp_line
			(start -0.7874 0.4064)
			(end 0.7874 0.4064)
			(stroke
				(width 0.1524)
				(type default)
			)
			(layer "B.SilkS")
		)
		(fp_line
			(start 0.7874 -0.4064)
			(end -0.7874 -0.4064)
			(stroke
				(width 0.1524)
				(type default)
			)
			(layer "B.SilkS")
		)
		(fp_line
			(start 0.7874 0.4064)
			(end 0.7874 -0.4064)
			(stroke
				(width 0.1524)
				(type default)
			)
			(layer "B.SilkS")
		)
		(fp_line
			(start -0.67945 -0.3048)
			(end -0.67945 0.3048)
			(stroke
				(width 0.1)
				(type default)
			)
			(layer "B.Fab")
		)
		(fp_line
			(start -0.67945 0.3048)
			(end -0.120396 0.3048)
			(stroke
				(width 0.1)
				(type default)
			)
			(layer "B.Fab")
		)
		(fp_line
			(start -0.12065 -0.3048)
			(end -0.67945 -0.3048)
			(stroke
				(width 0.1)
				(type default)
			)
			(layer "B.Fab")
		)
		(fp_line
			(start -0.12065 -0.2794)
			(end -0.12065 -0.3048)
			(stroke
				(width 0.1)
				(type default)
			)
			(layer "B.Fab")
		)
		(fp_line
			(start -0.120396 0.2794)
			(end 0.12065 0.2794)
			(stroke
				(width 0.1)
				(type default)
			)
			(layer "B.Fab")
		)
		(fp_line
			(start -0.120396 0.3048)
			(end -0.120396 0.2794)
			(stroke
				(width 0.1)
				(type default)
			)
			(layer "B.Fab")
		)
		(fp_line
			(start 0.12065 -0.305054)
			(end 0.12065 -0.2794)
			(stroke
				(width 0.1)
				(type default)
			)
			(layer "B.Fab")
		)
		(fp_line
			(start 0.12065 -0.2794)
			(end -0.12065 -0.2794)
			(stroke
				(width 0.1)
				(type default)
			)
			(layer "B.Fab")
		)
		(fp_line
			(start 0.12065 0.2794)
			(end 0.12065 0.3048)
			(stroke
				(width 0.1)
				(type default)
			)
			(layer "B.Fab")
		)
		(fp_line
			(start 0.12065 0.3048)
			(end 0.67945 0.3048)
			(stroke
				(width 0.1)
				(type default)
			)
			(layer "B.Fab")
		)
		(fp_line
			(start 0.67945 -0.305054)
			(end 0.12065 -0.305054)
			(stroke
				(width 0.1)
				(type default)
			)
			(layer "B.Fab")
		)
		(fp_line
			(start 0.67945 0.3048)
			(end 0.67945 -0.305054)
			(stroke
				(width 0.1)
				(type default)
			)
			(layer "B.Fab")
		)
		(pad "1" smd circle
			(at 0.40005 0 180)
			(size 0 0)
			(layers "B.Cu" "B.Mask" "B.Paste")
			(net "FM_CPU_MSMI_CATERR_LVT3_PLD_N")
		)
		(pad "2" smd circle
			(at -0.40005 0 180)
			(size 0 0)
			(layers "B.Cu" "B.Mask" "B.Paste")
			(net "FM_CPU_MSMI_CATERR_LVT3_N")
		)
	)
	(footprint ""
		(layer "B.Cu")
		(at 42.855896 -55.297324 180)
		(property "Reference" "L7"
			(at 0 0 0)
			(layer "B.SilkS")
			(hide yes)
			(effects
				(font
					(size 1.27 1.27)
				)
				(justify mirror)
			)
		)
		(property "Value" ""
			(at 0 0 0)
			(layer "B.Fab")
			(effects
				(font
					(size 1.27 1.27)
				)
				(justify mirror)
			)
		)
		(duplicate_pad_numbers_are_jumpers no)
		(fp_line
			(start 1.27 0.5842)
			(end 1.27 -0.5842)
			(stroke
				(width 0.1524)
				(type default)
			)
			(layer "B.SilkS")
		)
		(fp_line
			(start 1.27 -0.5588)
			(end 1.27 -0.5842)
			(stroke
				(width 0.1524)
				(type default)
			)
			(layer "B.SilkS")
		)
		(fp_line
			(start 1.27 -0.5842)
			(end -1.27 -0.5842)
			(stroke
				(width 0.1524)
				(type default)
			)
			(layer "B.SilkS")
		)
		(fp_line
			(start 0.127 0.5842)
			(end 0.127 -0.5842)
			(stroke
				(width 0.1524)
				(type default)
			)
			(layer "B.SilkS")
		)
		(fp_line
			(start -0.127 0.5842)
			(end -0.127 -0.5842)
			(stroke
				(width 0.1524)
				(type default)
			)
			(layer "B.SilkS")
		)
		(fp_line
			(start -1.27 0.5842)
			(end 1.27 0.5842)
			(stroke
				(width 0.1524)
				(type default)
			)
			(layer "B.SilkS")
		)
		(fp_line
			(start -1.27 0.5842)
			(end -1.27 -0.5842)
			(stroke
				(width 0.1524)
				(type default)
			)
			(layer "B.SilkS")
		)
		(fp_line
			(start 1.194308 0.406654)
			(end 1.194308 -0.406654)
			(stroke
				(width 0.1)
				(type default)
			)
			(layer "B.Fab")
		)
		(fp_line
			(start 1.194308 -0.406654)
			(end 0.9144 -0.406654)
			(stroke
				(width 0.1)
				(type default)
			)
			(layer "B.Fab")
		)
		(fp_line
			(start 0.9144 0.508)
			(end 0.9144 0.406654)
			(stroke
				(width 0.1)
				(type default)
			)
			(layer "B.Fab")
		)
		(fp_line
			(start 0.9144 0.406654)
			(end 1.194308 0.406654)
			(stroke
				(width 0.1)
				(type default)
			)
			(layer "B.Fab")
		)
		(fp_line
			(start 0.9144 -0.406654)
			(end 0.9144 -0.508)
			(stroke
				(width 0.1)
				(type default)
			)
			(layer "B.Fab")
		)
		(fp_line
			(start 0.9144 -0.508)
			(end -0.9144 -0.508)
			(stroke
				(width 0.1)
				(type default)
			)
			(layer "B.Fab")
		)
		(fp_line
			(start -0.9144 0.508)
			(end 0.9144 0.508)
			(stroke
				(width 0.1)
				(type default)
			)
			(layer "B.Fab")
		)
		(fp_line
			(start -0.9144 0.4064)
			(end -0.9144 0.508)
			(stroke
				(width 0.1)
				(type default)
			)
			(layer "B.Fab")
		)
		(fp_line
			(start -0.9144 -0.406654)
			(end -1.1938 -0.406654)
			(stroke
				(width 0.1)
				(type default)
			)
			(layer "B.Fab")
		)
		(fp_line
			(start -0.9144 -0.508)
			(end -0.9144 -0.406654)
			(stroke
				(width 0.1)
				(type default)
			)
			(layer "B.Fab")
		)
		(fp_line
			(start -1.1938 0.4064)
			(end -0.9144 0.4064)
			(stroke
				(width 0.1)
				(type default)
			)
			(layer "B.Fab")
		)
		(fp_line
			(start -1.1938 -0.406654)
			(end -1.1938 0.4064)
			(stroke
				(width 0.1)
				(type default)
			)
			(layer "B.Fab")
		)
		(pad "1" smd rect
			(at 0.7366 0 90)
			(size 0.7112 0.8128)
			(layers "B.Cu" "B.Mask" "B.Paste")
			(net "P3V3_AUX")
		)
		(pad "2" smd rect
			(at -0.7366 0 90)
			(size 0.7112 0.8128)
			(layers "B.Cu" "B.Mask" "B.Paste")
			(net "P3V3_STBY_DACAV33")
		)
	)
	(footprint ""
		(layer "B.Cu")
		(at 19.853656 -93.98 180)
		(property "Reference" "C243"
			(at 0 0 0)
			(layer "B.SilkS")
			(hide yes)
			(effects
				(font
					(size 1.27 1.27)
				)
				(justify mirror)
			)
		)
		(property "Value" ""
			(at 0 0 0)
			(layer "B.Fab")
			(effects
				(font
					(size 1.27 1.27)
				)
				(justify mirror)
			)
		)
		(duplicate_pad_numbers_are_jumpers no)
		(fp_line
			(start 0.69215 0.2921)
			(end 0.69215 -0.2921)
			(stroke
				(width 0.1524)
				(type default)
			)
			(layer "B.SilkS")
		)
		(fp_line
			(start 0.69215 -0.2921)
			(end -0.69215 -0.2921)
			(stroke
				(width 0.1524)
				(type default)
			)
			(layer "B.SilkS")
		)
		(fp_line
			(start -0.69215 0.2921)
			(end 0.69215 0.2921)
			(stroke
				(width 0.1524)
				(type default)
			)
			(layer "B.SilkS")
		)
		(fp_line
			(start -0.69215 -0.2921)
			(end -0.69215 0.2921)
			(stroke
				(width 0.1524)
				(type default)
			)
			(layer "B.SilkS")
		)
		(fp_line
			(start 0.51435 0.2794)
			(end 0.51435 -0.2794)
			(stroke
				(width 0.1)
				(type default)
			)
			(layer "B.Fab")
		)
		(fp_line
			(start 0.51435 -0.2794)
			(end -0.51435 -0.2794)
			(stroke
				(width 0.1)
				(type default)
			)
			(layer "B.Fab")
		)
		(fp_line
			(start -0.51435 0.2794)
			(end 0.51435 0.2794)
			(stroke
				(width 0.1)
				(type default)
			)
			(layer "B.Fab")
		)
		(fp_line
			(start -0.51435 -0.2794)
			(end -0.51435 0.2794)
			(stroke
				(width 0.1)
				(type default)
			)
			(layer "B.Fab")
		)
		(pad "1" smd circle
			(at 0.40005 0)
			(size 0 0)
			(layers "B.Cu" "B.Mask" "B.Paste")
			(net "VCCIO1")
		)
		(pad "2" smd circle
			(at -0.40005 0)
			(size 0 0)
			(layers "B.Cu" "B.Mask" "B.Paste")
			(net "GND")
		)
		(zone
			(layer "B.Cu")
			(hatch none 0.5)
			(connect_pads
				(clearance 0)
			)
			(min_thickness 0.25)
			(keepout
				(tracks not_allowed)
				(vias allowed)
				(pads allowed)
				(copperpour not_allowed)
				(footprints allowed)
			)
			(placement
				(enabled no)
				(sheetname "")
			)
			(fill
				(thermal_gap 0.5)
				(thermal_bridge_width 0.5)
				(island_removal_mode 0)
			)
			(polygon
				(pts
					(xy 19.663156 -94.06763) (xy 19.754596 -94.125796) (xy 19.953986 -94.125796) (xy 20.044156 -94.06763)
					(xy 20.044156 -93.89237) (xy 19.953986 -93.83395) (xy 19.754596 -93.83395) (xy 19.663156 -93.892116)
				)
			)
		)
	)
)
